# S9S_MB_2U (Grand Teton) — schematic netlist excerpt (pin names and nets, part order shuffled) for the footprints in the layout excerpt that follows; sources: Cadence DE-HDL packaged netlist, KiCad conversion of 03242023_DA0F0TMBIJ0_F0T_Motherboard_J_brd_V01_OCP.brd

PC605_P0_2  Q_CAP  1UF 16V 10% X6S  pkg C0402  page 271 : A = SW_P12V_PVCCFA_EHV_FIVRA_CPU0_L ; B = GND
R3705  Q_RES  10K 1% EMPTY  pkg 0402LF  page 233 : A = P3V3_AUX ; B = RST_SMB_SWITCH_N

(kicad_pcb
	(version 20260206)
	(generator "pcbnew")
	(generator_version "10.0")
	(general
		(thickness 1.6)
		(legacy_teardrops no)
	)
	(paper "A4")
	(title_block
		(title "03242023_DA0F0TMBIJ0_F0T_Motherboard_J_brd_V01_OCP.brd")
		(comment 1 "Grand Teton / footprints 3611-3612 of 6105")
	)
	(layers
		(0 "F.Cu" signal "TOP")
		(4 "In1.Cu" signal "GND")
		(6 "In2.Cu" signal "IN1")
		(8 "In3.Cu" signal "GND1")
		(10 "In4.Cu" signal "IN2")
		(12 "In5.Cu" signal "GND2")
		(14 "In6.Cu" signal "IN3")
		(16 "In7.Cu" signal "GND3")
		(18 "In8.Cu" signal "VCC")
		(20 "In9.Cu" signal "VCC1")
		(22 "In10.Cu" signal "GND4")
		(24 "In11.Cu" signal "IN4")
		(26 "In12.Cu" signal "GND5")
		(28 "In13.Cu" signal "IN5")
		(30 "In14.Cu" signal "GND6")
		(32 "In15.Cu" signal "IN6")
		(34 "In16.Cu" signal "GND7")
		(2 "B.Cu" signal "BOTTOM")
		(9 "F.Adhes" user "F.Adhesive")
		(11 "B.Adhes" user "B.Adhesive")
		(13 "F.Paste" user "Package Geometry/Pastemask Top")
		(15 "B.Paste" user "Package Geometry/Pastemask Bottom")
		(5 "F.SilkS" user "Ref Des/Silkscreen Top")
		(7 "B.SilkS" user "Ref Des/Silkscreen Bottom")
		(1 "F.Mask" user "Board Geometry/Soldermask Top")
		(3 "B.Mask" user "Board Geometry/Soldermask Bottom")
		(17 "Dwgs.User" user "User.Drawings")
		(19 "Cmts.User" user "User.Comments")
		(21 "Eco1.User" user "User.Eco1")
		(23 "Eco2.User" user "User.Eco2")
		(25 "Edge.Cuts" user "Board Geometry/Outline")
		(27 "Margin" user)
		(31 "F.CrtYd" user "Package Geometry/Place Bound Top")
		(29 "B.CrtYd" user "Package Geometry/Place Bound Bottom")
		(35 "F.Fab" user "Ref Des/Assembly Top")
		(33 "B.Fab" user "Ref Des/Assembly Bottom")
	)
	(footprint ""
		(layer "F.Cu")
		(at 51.593496 -116.52377)
		(property "Reference" "R3705"
			(at 0 0 0)
			(layer "F.SilkS")
			(hide yes)
			(effects
				(font
					(size 1.27 1.27)
				)
			)
		)
		(property "Value" ""
			(at 0 0 0)
			(layer "F.Fab")
			(effects
				(font
					(size 1.27 1.27)
				)
			)
		)
		(duplicate_pad_numbers_are_jumpers no)
		(fp_line
			(start -0.7874 -0.4064)
			(end 0.7874 -0.4064)
			(stroke
				(width 0.1524)
				(type default)
			)
			(layer "F.SilkS")
		)
		(fp_line
			(start -0.7874 0.4064)
			(end -0.7874 -0.4064)
			(stroke
				(width 0.1524)
				(type default)
			)
			(layer "F.SilkS")
		)
		(fp_line
			(start 0.7874 -0.4064)
			(end 0.7874 0.4064)
			(stroke
				(width 0.1524)
				(type default)
			)
			(layer "F.SilkS")
		)
		(fp_line
			(start 0.7874 0.4064)
			(end -0.7874 0.4064)
			(stroke
				(width 0.1524)
				(type default)
			)
			(layer "F.SilkS")
		)
		(fp_line
			(start -0.67945 -0.305054)
			(end -0.12065 -0.305054)
			(stroke
				(width 0.1)
				(type default)
			)
			(layer "F.Fab")
		)
		(fp_line
			(start -0.67945 0.3048)
			(end -0.67945 -0.305054)
			(stroke
				(width 0.1)
				(type default)
			)
			(layer "F.Fab")
		)
		(fp_line
			(start -0.12065 -0.305054)
			(end -0.12065 -0.2794)
			(stroke
				(width 0.1)
				(type default)
			)
			(layer "F.Fab")
		)
		(fp_line
			(start -0.12065 -0.2794)
			(end 0.12065 -0.2794)
			(stroke
				(width 0.1)
				(type default)
			)
			(layer "F.Fab")
		)
		(fp_line
			(start -0.12065 0.2794)
			(end -0.12065 0.3048)
			(stroke
				(width 0.1)
				(type default)
			)
			(layer "F.Fab")
		)
		(fp_line
			(start -0.12065 0.3048)
			(end -0.67945 0.3048)
			(stroke
				(width 0.1)
				(type default)
			)
			(layer "F.Fab")
		)
		(fp_line
			(start 0.120396 0.2794)
			(end -0.12065 0.2794)
			(stroke
				(width 0.1)
				(type default)
			)
			(layer "F.Fab")
		)
		(fp_line
			(start 0.120396 0.3048)
			(end 0.120396 0.2794)
			(stroke
				(width 0.1)
				(type default)
			)
			(layer "F.Fab")
		)
		(fp_line
			(start 0.12065 -0.3048)
			(end 0.67945 -0.3048)
			(stroke
				(width 0.1)
				(type default)
			)
			(layer "F.Fab")
		)
		(fp_line
			(start 0.12065 -0.2794)
			(end 0.12065 -0.3048)
			(stroke
				(width 0.1)
				(type default)
			)
			(layer "F.Fab")
		)
		(fp_line
			(start 0.67945 -0.3048)
			(end 0.67945 0.3048)
			(stroke
				(width 0.1)
				(type default)
			)
			(layer "F.Fab")
		)
		(fp_line
			(start 0.67945 0.3048)
			(end 0.120396 0.3048)
			(stroke
				(width 0.1)
				(type default)
			)
			(layer "F.Fab")
		)
		(pad "1" smd circle
			(at -0.40005 0)
			(size 0 0)
			(layers "F.Cu" "F.Mask" "F.Paste")
			(net "P3V3_AUX")
		)
		(pad "2" smd circle
			(at 0.40005 0)
			(size 0 0)
			(layers "F.Cu" "F.Mask" "F.Paste")
			(net "RST_SMB_SWITCH_N")
		)
	)
	(footprint ""
		(layer "F.Cu")
		(at 303.08804 -362.843826 -90)
		(property "Reference" "PC605_P0_2"
			(at 0 0 270)
			(layer "F.SilkS")
			(hide yes)
			(effects
				(font
					(size 1.27 1.27)
				)
			)
		)
		(property "Value" ""
			(at 0 0 270)
			(layer "F.Fab")
			(effects
				(font
					(size 1.27 1.27)
				)
			)
		)
		(duplicate_pad_numbers_are_jumpers no)
		(fp_line
			(start -0.7874 0.4064)
			(end -0.7874 -0.4064)
			(stroke
				(width 0.1524)
				(type default)
			)
			(layer "F.SilkS")
		)
		(fp_line
			(start 0.7874 0.4064)
			(end -0.7874 0.4064)
			(stroke
				(width 0.1524)
				(type default)
			)
			(layer "F.SilkS")
		)
		(fp_line
			(start -0.7874 -0.4064)
			(end 0.7874 -0.4064)
			(stroke
				(width 0.1524)
				(type default)
			)
			(layer "F.SilkS")
		)
		(fp_line
			(start 0.7874 -0.4064)
			(end 0.7874 0.4064)
			(stroke
				(width 0.1524)
				(type default)
			)
			(layer "F.SilkS")
		)
		(fp_line
			(start -0.67945 0.3048)
			(end -0.67945 -0.305054)
			(stroke
				(width 0.1)
				(type default)
			)
			(layer "F.Fab")
		)
		(fp_line
			(start -0.12065 0.3048)
			(end -0.67945 0.3048)
			(stroke
				(width 0.1)
				(type default)
			)
			(layer "F.Fab")
		)
		(fp_line
			(start 0.120396 0.3048)
			(end 0.120396 0.2794)
			(stroke
				(width 0.1)
				(type default)
			)
			(layer "F.Fab")
		)
		(fp_line
			(start 0.67945 0.3048)
			(end 0.120396 0.3048)
			(stroke
				(width 0.1)
				(type default)
			)
			(layer "F.Fab")
		)
		(fp_line
			(start -0.12065 0.2794)
			(end -0.12065 0.3048)
			(stroke
				(width 0.1)
				(type default)
			)
			(layer "F.Fab")
		)
		(fp_line
			(start 0.120396 0.2794)
			(end -0.12065 0.2794)
			(stroke
				(width 0.1)
				(type default)
			)
			(layer "F.Fab")
		)
		(fp_line
			(start -0.12065 -0.2794)
			(end 0.12065 -0.2794)
			(stroke
				(width 0.1)
				(type default)
			)
			(layer "F.Fab")
		)
		(fp_line
			(start 0.12065 -0.2794)
			(end 0.12065 -0.3048)
			(stroke
				(width 0.1)
				(type default)
			)
			(layer "F.Fab")
		)
		(fp_line
			(start 0.12065 -0.3048)
			(end 0.67945 -0.3048)
			(stroke
				(width 0.1)
				(type default)
			)
			(layer "F.Fab")
		)
		(fp_line
			(start 0.67945 -0.3048)
			(end 0.67945 0.3048)
			(stroke
				(width 0.1)
				(type default)
			)
			(layer "F.Fab")
		)
		(fp_line
			(start -0.67945 -0.305054)
			(end -0.12065 -0.305054)
			(stroke
				(width 0.1)
				(type default)
			)
			(layer "F.Fab")
		)
		(fp_line
			(start -0.12065 -0.305054)
			(end -0.12065 -0.2794)
			(stroke
				(width 0.1)
				(type default)
			)
			(layer "F.Fab")
		)
		(pad "1" smd circle
			(at -0.40005 0 270)
			(size 0 0)
			(layers "F.Cu" "F.Mask" "F.Paste")
			(net "SW_P12V_PVCCFA_EHV_FIVRA_CPU0_L")
		)
		(pad "2" smd circle
			(at 0.40005 0 270)
			(size 0 0)
			(layers "F.Cu" "F.Mask" "F.Paste")
			(net "GND")
		)
	)
)
